(kicad_pcb
	(version 20260206)
	(generator "pcbnew")
	(generator_version "10.0")
	(general
		(thickness 1.6)
		(legacy_teardrops no)
	)
	(paper "A4")
	(title_block
		(title "fcb — 12433-1M.1206WZS1330.brd")
		(comment 1 "Open Vault / Knox (Wiwynn) / footprints 139-145 of 495")
	)
	(layers
		(0 "F.Cu" signal "TOP")
		(4 "In1.Cu" signal "L2GND")
		(6 "In2.Cu" signal "L3VCC")
		(2 "B.Cu" signal "BOTTOM")
		(9 "F.Adhes" user "F.Adhesive")
		(11 "B.Adhes" user "B.Adhesive")
		(13 "F.Paste" user "Package Geometry/Pastemask Top")
		(15 "B.Paste" user "Package Geometry/Pastemask Bottom")
		(5 "F.SilkS" user "Ref Des/Silkscreen Top")
		(7 "B.SilkS" user "Ref Des/Silkscreen Bottom")
		(1 "F.Mask" user "Board Geometry/Soldermask Top")
		(3 "B.Mask" user "Board Geometry/Soldermask Bottom")
		(17 "Dwgs.User" user "User.Drawings")
		(19 "Cmts.User" user "User.Comments")
		(21 "Eco1.User" user "User.Eco1")
		(23 "Eco2.User" user "User.Eco2")
		(25 "Edge.Cuts" user "Board Geometry/Outline")
		(27 "Margin" user)
		(31 "F.CrtYd" user "Package Geometry/Place Bound Top")
		(29 "B.CrtYd" user "Package Geometry/Place Bound Bottom")
		(35 "F.Fab" user "Ref Des/Assembly Top")
		(33 "B.Fab" user "Ref Des/Assembly Bottom")
	)
	(footprint ""
		(layer "F.Cu")
		(at 43.942 -95.7326 90)
		(property "Reference" "TC5"
			(at 0 0 90)
			(layer "F.SilkS")
			(hide yes)
			(effects
				(font
					(size 1.27 1.27)
				)
			)
		)
		(property "Value" "ST68U16VDM-1-GP"
			(at 0 -9.6012 90)
			(unlocked yes)
			(layer "F.Fab")
			(hide yes)
			(effects
				(font
					(size 1.016 1.016)
					(thickness 0.1524)
				)
			)
		)
		(property "Device Type" "CT7343H79"
			(at 0 -11.1252 90)
			(unlocked yes)
			(layer "F.Fab")
			(hide yes)
			(effects
				(font
					(size 1.016 1.016)
					(thickness 0.1524)
				)
			)
		)
		(duplicate_pad_numbers_are_jumpers no)
		(fp_line
			(start 2.286 -4.8768)
			(end -2.286 -4.8768)
			(stroke
				(width 0.1524)
				(type default)
			)
			(layer "F.SilkS")
		)
		(fp_line
			(start -2.286 -4.8768)
			(end -2.286 -2.032)
			(stroke
				(width 0.1524)
				(type default)
			)
			(layer "F.SilkS")
		)
		(fp_line
			(start 2.1082 -4.699)
			(end -2.1082 -4.699)
			(stroke
				(width 0.508)
				(type default)
			)
			(layer "F.SilkS")
		)
		(fp_line
			(start 2.286 -2.032)
			(end 2.286 -4.8768)
			(stroke
				(width 0.1524)
				(type default)
			)
			(layer "F.SilkS")
		)
		(fp_line
			(start 2.286 2.032)
			(end 2.286 4.8768)
			(stroke
				(width 0.1524)
				(type default)
			)
			(layer "F.SilkS")
		)
		(fp_line
			(start 2.286 4.8768)
			(end -2.286 4.8768)
			(stroke
				(width 0.1524)
				(type default)
			)
			(layer "F.SilkS")
		)
		(fp_line
			(start -2.286 4.8768)
			(end -2.286 2.032)
			(stroke
				(width 0.1524)
				(type default)
			)
			(layer "F.SilkS")
		)
		(fp_rect
			(start -2.1463 3.6449)
			(end 2.1463 -3.6449)
			(stroke
				(width 0)
				(type default)
			)
			(fill no)
			(layer "F.CrtYd")
		)
		(fp_poly
			(pts
				(xy -2.54 4.953) (xy -2.54 4.2926) (xy -3.81 4.2926) (xy -3.81 -4.2926) (xy -2.54 -4.2926) (xy -2.54 -4.953)
				(xy 2.54 -4.953) (xy 2.54 -4.2926) (xy 3.81 -4.2926) (xy 3.81 -1.6256) (xy 2.1463 -1.6256) (xy 2.1463 -3.6449)
				(xy -2.1463 -3.6449) (xy -2.1463 3.6449) (xy 2.1463 3.6449) (xy 2.1463 -1.6129) (xy 3.81 -1.6129)
				(xy 3.81 4.2926) (xy 2.54 4.2926) (xy 2.54 4.953)
			)
			(stroke
				(width 0)
				(type default)
			)
			(fill no)
			(layer "F.CrtYd")
		)
		(fp_rect
			(start 2.54 4.2926)
			(end 3.81 -4.2926)
			(stroke
				(width 0)
				(type default)
			)
			(fill no)
			(layer "F.Fab")
		)
		(fp_rect
			(start -3.81 4.2926)
			(end -2.54 -4.2926)
			(stroke
				(width 0)
				(type default)
			)
			(fill no)
			(layer "F.Fab")
		)
		(fp_rect
			(start -2.54 4.953)
			(end 2.54 -4.953)
			(stroke
				(width 0)
				(type default)
			)
			(fill no)
			(layer "F.Fab")
		)
		(pad "1" smd rect
			(at 0 -3.1496 90)
			(size 2.413 2.286)
			(layers "F.Cu" "F.Mask" "F.Paste")
			(net "P12VL")
		)
		(pad "2" smd rect
			(at 0 3.1496 90)
			(size 2.413 2.286)
			(layers "F.Cu" "F.Mask" "F.Paste")
			(net "GND")
		)
		(zone
			(layer "F.Cu")
			(hatch none 0.5)
			(connect_pads
				(clearance 0)
			)
			(min_thickness 0.25)
			(keepout
				(tracks allowed)
				(vias not_allowed)
				(pads allowed)
				(copperpour not_allowed)
				(footprints allowed)
			)
			(placement
				(enabled no)
				(sheetname "")
			)
			(fill
				(thermal_gap 0.5)
				(thermal_bridge_width 0.5)
				(island_removal_mode 0)
			)
			(polygon
				(pts
					(xy 42.2529 -97.2439) (xy 39.3446 -97.2439) (xy 39.3446 -94.2213) (xy 42.2402 -94.2213) (xy 42.5704 -94.2213)
					(xy 42.5704 -97.2439)
				)
			)
		)
		(zone
			(layer "F.Cu")
			(hatch none 0.5)
			(connect_pads
				(clearance 0)
			)
			(min_thickness 0.25)
			(keepout
				(tracks allowed)
				(vias not_allowed)
				(pads allowed)
				(copperpour not_allowed)
				(footprints allowed)
			)
			(placement
				(enabled no)
				(sheetname "")
			)
			(fill
				(thermal_gap 0.5)
				(thermal_bridge_width 0.5)
				(island_removal_mode 0)
			)
			(polygon
				(pts
					(xy 48.5394 -94.2213) (xy 48.5394 -97.2439) (xy 45.6438 -97.2439) (xy 45.3136 -97.2439) (xy 45.3136 -94.2213)
					(xy 45.6438 -94.2213)
				)
			)
		)
	)
	(footprint ""
		(layer "F.Cu")
		(at 47.625 -408.051 90)
		(property "Reference" "PC7"
			(at 0 0 90)
			(layer "F.SilkS")
			(hide yes)
			(effects
				(font
					(size 1.27 1.27)
				)
			)
		)
		(property "Value" "SC1U25V5KX-1GP"
			(at -0.0762 -6.1214 90)
			(unlocked yes)
			(layer "F.Fab")
			(hide yes)
			(effects
				(font
					(size 1.016 1.016)
					(thickness 0.1524)
				)
			)
		)
		(property "Device Type" "C805H58"
			(at -0.0762 -8.1534 90)
			(unlocked yes)
			(layer "F.Fab")
			(hide yes)
			(effects
				(font
					(size 1.016 1.016)
					(thickness 0.1524)
				)
			)
		)
		(duplicate_pad_numbers_are_jumpers no)
		(fp_line
			(start 0.635 0)
			(end -0.635 0)
			(stroke
				(width 0.508)
				(type default)
			)
			(layer "F.SilkS")
		)
		(fp_rect
			(start -0.9652 1.778)
			(end 0.9652 -1.778)
			(stroke
				(width 0)
				(type default)
			)
			(fill no)
			(layer "F.CrtYd")
		)
		(fp_poly
			(pts
				(xy -0.9652 -1.778) (xy 0.9652 -1.778) (xy 0.9652 1.778) (xy -0.9652 1.778)
			)
			(stroke
				(width 0)
				(type default)
			)
			(fill no)
			(layer "F.Fab")
		)
		(pad "1" smd rect
			(at 0 -0.9652 90)
			(size 1.397 1.143)
			(layers "F.Cu" "F.Mask" "F.Paste")
			(net "P12V_SENSE_TRACE")
		)
		(pad "2" smd rect
			(at 0 0.9652 90)
			(size 1.397 1.143)
			(layers "F.Cu" "F.Mask" "F.Paste")
			(net "GND")
		)
	)
	(footprint ""
		(layer "F.Cu")
		(at 36.9062 -147.447 180)
		(property "Reference" "PR115"
			(at 0 0 180)
			(layer "F.SilkS")
			(hide yes)
			(effects
				(font
					(size 1.27 1.27)
				)
			)
		)
		(property "Value" "20KR2F-L-GP"
			(at 0.064008 -3.993896 180)
			(unlocked yes)
			(layer "F.Fab")
			(hide yes)
			(effects
				(font
					(size 1.016 1.016)
					(thickness 0.1524)
				)
			)
		)
		(property "Device Type" "R402H16"
			(at 0.064008 -5.517896 180)
			(unlocked yes)
			(layer "F.Fab")
			(hide yes)
			(effects
				(font
					(size 1.016 1.016)
					(thickness 0.1524)
				)
			)
		)
		(duplicate_pad_numbers_are_jumpers no)
		(fp_line
			(start 0.508 -0.9398)
			(end -0.508 -0.9398)
			(stroke
				(width 0.1524)
				(type default)
			)
			(layer "F.SilkS")
		)
		(fp_line
			(start -0.508 -0.9398)
			(end -0.508 0.9398)
			(stroke
				(width 0.1524)
				(type default)
			)
			(layer "F.SilkS")
		)
		(fp_rect
			(start -0.508 0.9398)
			(end 0.508 -0.9398)
			(stroke
				(width 0)
				(type default)
			)
			(fill no)
			(layer "F.CrtYd")
		)
		(fp_rect
			(start -0.508 0.9398)
			(end 0.508 -0.9398)
			(stroke
				(width 0)
				(type default)
			)
			(fill no)
			(layer "F.Fab")
		)
		(pad "1" smd custom
			(at 0 -0.4445 180)
			(size 0.1397 0.1397)
			(layers "F.Cu" "F.Mask" "F.Paste")
			(net "P12VL_2490_PROG")
			(options
				(clearance outline)
				(anchor circle)
			)
			(primitives
				(gr_poly
					(pts
						(arc
							(start -0.1778 -0.2794)
							(mid -0.249642 -0.249642)
							(end -0.2794 -0.1778)
						)
						(arc
							(start -0.2794 0.1778)
							(mid -0.249642 0.249642)
							(end -0.1778 0.2794)
						)
						(arc
							(start 0.1778 0.2794)
							(mid 0.249642 0.249642)
							(end 0.2794 0.1778)
						)
						(arc
							(start 0.2794 -0.1778)
							(mid 0.249642 -0.249642)
							(end 0.1778 -0.2794)
						)
					)
					(width 0)
					(fill yes)
				)
			)
		)
		(pad "2" smd custom
			(at 0 0.4445 180)
			(size 0.1397 0.1397)
			(layers "F.Cu" "F.Mask" "F.Paste")
			(net "GND")
			(options
				(clearance outline)
				(anchor circle)
			)
			(primitives
				(gr_poly
					(pts
						(arc
							(start -0.1778 -0.2794)
							(mid -0.249642 -0.249642)
							(end -0.2794 -0.1778)
						)
						(arc
							(start -0.2794 0.1778)
							(mid -0.249642 0.249642)
							(end -0.1778 0.2794)
						)
						(arc
							(start 0.1778 0.2794)
							(mid 0.249642 0.249642)
							(end 0.2794 0.1778)
						)
						(arc
							(start 0.2794 -0.1778)
							(mid 0.249642 -0.249642)
							(end 0.1778 -0.2794)
						)
					)
					(width 0)
					(fill yes)
				)
			)
		)
	)
	(footprint ""
		(layer "F.Cu")
		(at 15.494 -60.5282 180)
		(property "Reference" "R359"
			(at 0 0 180)
			(layer "F.SilkS")
			(hide yes)
			(effects
				(font
					(size 1.27 1.27)
				)
			)
		)
		(property "Value" "10KR2F-2-GP"
			(at 0.064008 -3.993896 180)
			(unlocked yes)
			(layer "F.Fab")
			(hide yes)
			(effects
				(font
					(size 1.016 1.016)
					(thickness 0.1524)
				)
			)
		)
		(property "Device Type" "R402H16"
			(at 0.064008 -5.517896 180)
			(unlocked yes)
			(layer "F.Fab")
			(hide yes)
			(effects
				(font
					(size 1.016 1.016)
					(thickness 0.1524)
				)
			)
		)
		(duplicate_pad_numbers_are_jumpers no)
		(fp_line
			(start 0.508 -0.9398)
			(end -0.508 -0.9398)
			(stroke
				(width 0.1524)
				(type default)
			)
			(layer "F.SilkS")
		)
		(fp_line
			(start -0.508 -0.9398)
			(end -0.508 0.9398)
			(stroke
				(width 0.1524)
				(type default)
			)
			(layer "F.SilkS")
		)
		(fp_rect
			(start -0.508 0.9398)
			(end 0.508 -0.9398)
			(stroke
				(width 0)
				(type default)
			)
			(fill no)
			(layer "F.CrtYd")
		)
		(fp_rect
			(start -0.508 0.9398)
			(end 0.508 -0.9398)
			(stroke
				(width 0)
				(type default)
			)
			(fill no)
			(layer "F.Fab")
		)
		(pad "1" smd custom
			(at 0 -0.4445 180)
			(size 0.1397 0.1397)
			(layers "F.Cu" "F.Mask" "F.Paste")
			(net "P3V3")
			(options
				(clearance outline)
				(anchor circle)
			)
			(primitives
				(gr_poly
					(pts
						(arc
							(start -0.1778 -0.2794)
							(mid -0.249642 -0.249642)
							(end -0.2794 -0.1778)
						)
						(arc
							(start -0.2794 0.1778)
							(mid -0.249642 0.249642)
							(end -0.1778 0.2794)
						)
						(arc
							(start 0.1778 0.2794)
							(mid 0.249642 0.249642)
							(end 0.2794 0.1778)
						)
						(arc
							(start 0.2794 -0.1778)
							(mid 0.249642 -0.249642)
							(end 0.1778 -0.2794)
						)
					)
					(width 0)
					(fill yes)
				)
			)
		)
		(pad "2" smd custom
			(at 0 0.4445 180)
			(size 0.1397 0.1397)
			(layers "F.Cu" "F.Mask" "F.Paste")
			(net "UPPER_TRAY_ID")
			(options
				(clearance outline)
				(anchor circle)
			)
			(primitives
				(gr_poly
					(pts
						(arc
							(start -0.1778 -0.2794)
							(mid -0.249642 -0.249642)
							(end -0.2794 -0.1778)
						)
						(arc
							(start -0.2794 0.1778)
							(mid -0.249642 0.249642)
							(end -0.1778 0.2794)
						)
						(arc
							(start 0.1778 0.2794)
							(mid 0.249642 0.249642)
							(end 0.2794 0.1778)
						)
						(arc
							(start 0.2794 -0.1778)
							(mid 0.249642 -0.249642)
							(end 0.1778 -0.2794)
						)
					)
					(width 0)
					(fill yes)
				)
			)
		)
	)
	(footprint ""
		(layer "F.Cu")
		(at 31.96209 -150.781766 180)
		(property "Reference" "TP6"
			(at 0 0 180)
			(layer "F.SilkS")
			(hide yes)
			(effects
				(font
					(size 1.27 1.27)
				)
			)
		)
		(property "Value" "TPAD32-GP"
			(at 0 -3.166364 180)
			(unlocked yes)
			(layer "F.Fab")
			(hide yes)
			(effects
				(font
					(size 1.016 1.016)
					(thickness 0.1524)
				)
			)
		)
		(property "Device Type" "TPAD32"
			(at 0 -4.690618 180)
			(unlocked yes)
			(layer "F.Fab")
			(hide yes)
			(effects
				(font
					(size 1.016 1.016)
					(thickness 0.1524)
				)
			)
		)
		(duplicate_pad_numbers_are_jumpers no)
		(fp_poly
			(pts
				(arc
					(start 0.7112 0)
					(mid -0.7112 0)
					(end 0.7112 0)
				)
			)
			(stroke
				(width 0)
				(type default)
			)
			(fill no)
			(layer "F.CrtYd")
		)
		(fp_poly
			(pts
				(arc
					(start 0.7112 0)
					(mid -0.7112 0)
					(end 0.7112 0)
				)
			)
			(stroke
				(width 0)
				(type default)
			)
			(fill no)
			(layer "F.Fab")
		)
		(pad "1" smd circle
			(at 0 0 180)
			(size 0.8128 0.8128)
			(layers "F.Cu" "F.Mask" "F.Paste")
			(net "NCT7904_VSEN8")
		)
	)
	(footprint ""
		(layer "F.Cu")
		(at 14.8844 -40.4622 90)
		(property "Reference" "R172"
			(at 0 0 90)
			(layer "F.SilkS")
			(hide yes)
			(effects
				(font
					(size 1.27 1.27)
				)
			)
		)
		(property "Value" "0R2J-2-GP"
			(at 0.064008 -3.993896 90)
			(unlocked yes)
			(layer "F.Fab")
			(hide yes)
			(effects
				(font
					(size 1.016 1.016)
					(thickness 0.1524)
				)
			)
		)
		(property "Device Type" "R402H16"
			(at 0.064008 -5.517896 90)
			(unlocked yes)
			(layer "F.Fab")
			(hide yes)
			(effects
				(font
					(size 1.016 1.016)
					(thickness 0.1524)
				)
			)
		)
		(duplicate_pad_numbers_are_jumpers no)
		(fp_line
			(start 0.508 -0.9398)
			(end -0.508 -0.9398)
			(stroke
				(width 0.1524)
				(type default)
			)
			(layer "F.SilkS")
		)
		(fp_line
			(start -0.508 -0.9398)
			(end -0.508 0.9398)
			(stroke
				(width 0.1524)
				(type default)
			)
			(layer "F.SilkS")
		)
		(fp_rect
			(start -0.508 0.9398)
			(end 0.508 -0.9398)
			(stroke
				(width 0)
				(type default)
			)
			(fill no)
			(layer "F.CrtYd")
		)
		(fp_rect
			(start -0.508 0.9398)
			(end 0.508 -0.9398)
			(stroke
				(width 0)
				(type default)
			)
			(fill no)
			(layer "F.Fab")
		)
		(pad "1" smd custom
			(at 0 -0.4445 90)
			(size 0.1397 0.1397)
			(layers "F.Cu" "F.Mask" "F.Paste")
			(net "SELF_1B_HB")
			(options
				(clearance outline)
				(anchor circle)
			)
			(primitives
				(gr_poly
					(pts
						(arc
							(start -0.1778 -0.2794)
							(mid -0.249642 -0.249642)
							(end -0.2794 -0.1778)
						)
						(arc
							(start -0.2794 0.1778)
							(mid -0.249642 0.249642)
							(end -0.1778 0.2794)
						)
						(arc
							(start 0.1778 0.2794)
							(mid 0.249642 0.249642)
							(end 0.2794 0.1778)
						)
						(arc
							(start 0.2794 -0.1778)
							(mid 0.249642 -0.249642)
							(end 0.1778 -0.2794)
						)
					)
					(width 0)
					(fill yes)
				)
			)
		)
		(pad "2" smd custom
			(at 0 0.4445 90)
			(size 0.1397 0.1397)
			(layers "F.Cu" "F.Mask" "F.Paste")
			(net "SEB_PEER_2B_HB")
			(options
				(clearance outline)
				(anchor circle)
			)
			(primitives
				(gr_poly
					(pts
						(arc
							(start -0.1778 -0.2794)
							(mid -0.249642 -0.249642)
							(end -0.2794 -0.1778)
						)
						(arc
							(start -0.2794 0.1778)
							(mid -0.249642 0.249642)
							(end -0.1778 0.2794)
						)
						(arc
							(start 0.1778 0.2794)
							(mid 0.249642 0.249642)
							(end 0.2794 0.1778)
						)
						(arc
							(start 0.2794 -0.1778)
							(mid 0.249642 -0.249642)
							(end 0.1778 -0.2794)
						)
					)
					(width 0)
					(fill yes)
				)
			)
		)
	)
	(footprint ""
		(layer "F.Cu")
		(at 15.494 -168.2242 90)
		(property "Reference" "C34"
			(at 0 0 90)
			(layer "F.SilkS")
			(hide yes)
			(effects
				(font
					(size 1.27 1.27)
				)
			)
		)
		(property "Value" "SC1U25V3KX-1-GP"
			(at 0 -2.8194 90)
			(unlocked yes)
			(layer "F.Fab")
			(hide yes)
			(effects
				(font
					(size 1.016 1.016)
					(thickness 0.1524)
				)
			)
		)
		(property "Device Type" "C603H36"
			(at 0 -4.3434 90)
			(unlocked yes)
			(layer "F.Fab")
			(hide yes)
			(effects
				(font
					(size 1.016 1.016)
					(thickness 0.1524)
				)
			)
		)
		(duplicate_pad_numbers_are_jumpers no)
		(fp_line
			(start 0.508 0)
			(end -0.508 0)
			(stroke
				(width 0.2032)
				(type default)
			)
			(layer "F.SilkS")
		)
		(fp_rect
			(start -0.5842 1.3335)
			(end 0.5842 -1.3335)
			(stroke
				(width 0)
				(type default)
			)
			(fill no)
			(layer "F.CrtYd")
		)
		(fp_rect
			(start -0.5842 1.3335)
			(end 0.5842 -1.3335)
			(stroke
				(width 0)
				(type default)
			)
			(fill no)
			(layer "F.Fab")
		)
		(pad "1" smd custom
			(at 0 -0.762 90)
			(size 0.2159 0.2159)
			(layers "F.Cu" "F.Mask" "F.Paste")
			(net "P12V")
			(options
				(clearance outline)
				(anchor circle)
			)
			(primitives
				(gr_poly
					(pts
						(arc
							(start -0.3302 -0.4318)
							(mid -0.402042 -0.402042)
							(end -0.4318 -0.3302)
						)
						(arc
							(start -0.4318 0.3302)
							(mid -0.402042 0.402042)
							(end -0.3302 0.4318)
						)
						(arc
							(start 0.3302 0.4318)
							(mid 0.402042 0.402042)
							(end 0.4318 0.3302)
						)
						(arc
							(start 0.4318 -0.3302)
							(mid 0.402042 -0.402042)
							(end 0.3302 -0.4318)
						)
					)
					(width 0)
					(fill yes)
				)
			)
		)
		(pad "2" smd custom
			(at 0 0.762 90)
			(size 0.2159 0.2159)
			(layers "F.Cu" "F.Mask" "F.Paste")
			(net "GND")
			(options
				(clearance outline)
				(anchor circle)
			)
			(primitives
				(gr_poly
					(pts
						(arc
							(start -0.3302 -0.4318)
							(mid -0.402042 -0.402042)
							(end -0.4318 -0.3302)
						)
						(arc
							(start -0.4318 0.3302)
							(mid -0.402042 0.402042)
							(end -0.3302 0.4318)
						)
						(arc
							(start 0.3302 0.4318)
							(mid 0.402042 0.402042)
							(end 0.4318 0.3302)
						)
						(arc
							(start 0.4318 -0.3302)
							(mid 0.402042 -0.402042)
							(end 0.3302 -0.4318)
						)
					)
					(width 0)
					(fill yes)
				)
			)
		)
	)
)
